(kicad_pcb
	(version 20241229)
	(generator "pcbnew")
	(generator_version "9.0")
	(general
		(thickness 1.711)
		(legacy_teardrops no)
	)
	(paper "A4")
	(title_block
		(title "Antmicro Baseboard for Jetson AGX Thor")
		(date "2026-02-18")
		(rev "1.1.0")
		(company "Antmicro Ltd")
		(comment 1 "www.antmicro.com")
		(comment 9 "footprints 980-984 of 1170")
	)
	(layers
		(0 "F.Cu" signal)
		(4 "In1.Cu" signal)
		(6 "In2.Cu" signal)
		(8 "In3.Cu" signal)
		(10 "In4.Cu" jumper)
		(12 "In5.Cu" signal)
		(14 "In6.Cu" signal)
		(16 "In7.Cu" signal)
		(18 "In8.Cu" signal)
		(2 "B.Cu" signal)
		(9 "F.Adhes" user "F.Adhesive")
		(11 "B.Adhes" user "B.Adhesive")
		(13 "F.Paste" user)
		(15 "B.Paste" user)
		(5 "F.SilkS" user "F.Silkscreen")
		(7 "B.SilkS" user "B.Silkscreen")
		(1 "F.Mask" user)
		(3 "B.Mask" user)
		(17 "Dwgs.User" user "User.Drawings")
		(19 "Cmts.User" user "User.Comments")
		(21 "Eco1.User" user "User.Eco1")
		(23 "Eco2.User" user "User.Eco2")
		(25 "Edge.Cuts" user)
		(27 "Margin" user)
		(31 "F.CrtYd" user "F.Courtyard")
		(29 "B.CrtYd" user "B.Courtyard")
		(35 "F.Fab" user)
		(33 "B.Fab" user)
	)
	(footprint "antmicro-footprints:C_0402_1005Metric"
		(layer "B.Cu")
		(at 235.8 96.6)
		(descr "Capacitor SMD 0402")
		(tags "capacitor SMD 0402")
		(property "Reference" "C137"
			(at 1.1 0.4 0)
			(layer "B.SilkS")
			(effects
				(font
					(size 0.7 0.7)
					(thickness 0.15)
				)
				(justify right top mirror)
			)
		)
		(property "Value" "C_100n_0402"
			(at -1.022927 -2.155213 0)
			(layer "B.Fab")
			(effects
				(font
					(size 0.7 0.7)
					(thickness 0.15)
				)
				(justify right top mirror)
			)
		)
		(property "Datasheet" "https://www.murata.com/products/productdetail?partno=GRM155R61H104KE14%23"
			(at 0 0 0)
			(layer "B.Fab")
			(hide yes)
			(effects
				(font
					(size 1.27 1.27)
					(thickness 0.15)
				)
				(justify mirror)
			)
		)
		(property "Description" "SMD Multilayer Ceramic Capacitor, 0.1 µF, 50 V, 0402 [1005 Metric], ± 10%, X5R, GRM Series"
			(at 0 0 0)
			(layer "B.Fab")
			(hide yes)
			(effects
				(font
					(size 1.27 1.27)
					(thickness 0.15)
				)
				(justify mirror)
			)
		)
		(property "Manufacturer" "Murata"
			(at 0 0 180)
			(unlocked yes)
			(layer "B.Fab")
			(hide yes)
			(effects
				(font
					(size 1 1)
					(thickness 0.15)
				)
				(justify mirror)
			)
		)
		(property "MPN" "GRM155R61H104KE14D"
			(at 0 0 180)
			(unlocked yes)
			(layer "B.Fab")
			(hide yes)
			(effects
				(font
					(size 1 1)
					(thickness 0.15)
				)
				(justify mirror)
			)
		)
		(property "Val" "100n"
			(at 0 0 180)
			(unlocked yes)
			(layer "B.Fab")
			(hide yes)
			(effects
				(font
					(size 1 1)
					(thickness 0.15)
				)
				(justify mirror)
			)
		)
		(property "License" "Apache-2.0"
			(at 0 0 180)
			(unlocked yes)
			(layer "B.Fab")
			(hide yes)
			(effects
				(font
					(size 1 1)
					(thickness 0.15)
				)
				(justify mirror)
			)
		)
		(property "Author" "Antmicro"
			(at 0 0 180)
			(unlocked yes)
			(layer "B.Fab")
			(hide yes)
			(effects
				(font
					(size 1 1)
					(thickness 0.15)
				)
				(justify mirror)
			)
		)
		(property "Voltage" "50V"
			(at 0 0 180)
			(unlocked yes)
			(layer "B.Fab")
			(hide yes)
			(effects
				(font
					(size 1 1)
					(thickness 0.15)
				)
				(justify mirror)
			)
		)
		(property "Dielectric" "X5R"
			(at 0 0 180)
			(unlocked yes)
			(layer "B.Fab")
			(hide yes)
			(effects
				(font
					(size 1 1)
					(thickness 0.15)
				)
				(justify mirror)
			)
		)
		(sheetname "/USB DP Alt mode/")
		(sheetfile "usb_dp.kicad_sch")
		(attr smd)
		(fp_poly
			(pts
				(xy -0.925 0.47) (xy -0.925 -0.47) (xy 0.925 -0.47) (xy 0.925 0.47)
			)
			(stroke
				(width 0.05)
				(type default)
			)
			(fill no)
			(layer "B.CrtYd")
		)
		(fp_line
			(start -0.494 -0.248)
			(end -0.494 0.25)
			(stroke
				(width 0.15)
				(type solid)
			)
			(layer "B.Fab")
		)
		(fp_line
			(start -0.494 0.25)
			(end 0.504 0.25)
			(stroke
				(width 0.15)
				(type solid)
			)
			(layer "B.Fab")
		)
		(fp_line
			(start 0.504 -0.248)
			(end -0.494 -0.248)
			(stroke
				(width 0.15)
				(type solid)
			)
			(layer "B.Fab")
		)
		(fp_line
			(start 0.504 0.25)
			(end 0.504 -0.248)
			(stroke
				(width 0.15)
				(type solid)
			)
			(layer "B.Fab")
		)
		(fp_text user "${REFERENCE}"
			(at -0.939 -4.599 0)
			(layer "B.Fab")
			(effects
				(font
					(size 0.7 0.7)
					(thickness 0.15)
				)
				(justify right top mirror)
			)
		)
		(fp_text user "License: Apache-2.0"
			(at -0.939 -5.799 0)
			(layer "B.Fab")
			(effects
				(font
					(size 0.7 0.7)
					(thickness 0.15)
				)
				(justify right top mirror)
			)
		)
		(fp_text user "Author: Antmicro"
			(at -0.939 -3.399 0)
			(layer "B.Fab")
			(effects
				(font
					(size 0.7 0.7)
					(thickness 0.15)
				)
				(justify right top mirror)
			)
		)
		(pad "1" smd roundrect
			(at -0.48 0)
			(size 0.59 0.64)
			(layers "B.Cu" "B.Mask" "B.Paste")
			(roundrect_rratio 0.25)
			(net 5 "+5V")
			(pintype "passive")
		)
		(pad "2" smd roundrect
			(at 0.48 0)
			(size 0.59 0.64)
			(layers "B.Cu" "B.Mask" "B.Paste")
			(roundrect_rratio 0.25)
			(net 1 "GND")
			(pintype "passive")
		)
	)
	(footprint "antmicro-footprints:SOT-523"
		(layer "B.Cu")
		(at 161.16 59.78 -90)
		(property "Reference" "Q4"
			(at 0.12 1.26 90)
			(layer "B.SilkS")
			(effects
				(font
					(size 0.7 0.7)
					(thickness 0.15)
				)
				(justify left bottom mirror)
			)
		)
		(property "Value" "DMG1012T-7"
			(at 0.1 -1.824 90)
			(layer "B.Fab")
			(effects
				(font
					(size 0.7 0.7)
					(thickness 0.15)
				)
				(justify left bottom mirror)
			)
		)
		(property "Datasheet" "https://www.diodes.com/assets/Datasheets/ds31783.pdf"
			(at 0 0 90)
			(layer "B.Fab")
			(hide yes)
			(effects
				(font
					(size 1.27 1.27)
					(thickness 0.15)
				)
				(justify mirror)
			)
		)
		(property "Description" "Power MOSFET, N Channel, 20 V, 630 mA, 0.3 ohm, SOT-523, Surface Mount"
			(at 0 0 90)
			(layer "B.Fab")
			(hide yes)
			(effects
				(font
					(size 1.27 1.27)
					(thickness 0.15)
				)
				(justify mirror)
			)
		)
		(property "MPN" "DMG1012T-7"
			(at 0 0 90)
			(unlocked yes)
			(layer "B.Fab")
			(hide yes)
			(effects
				(font
					(size 1 1)
					(thickness 0.15)
				)
				(justify mirror)
			)
		)
		(property "Manufacturer" "Diodes Incorporated"
			(at 0 0 90)
			(unlocked yes)
			(layer "B.Fab")
			(hide yes)
			(effects
				(font
					(size 1 1)
					(thickness 0.15)
				)
				(justify mirror)
			)
		)
		(property "Author" "Antmicro"
			(at 0 0 90)
			(unlocked yes)
			(layer "B.Fab")
			(hide yes)
			(effects
				(font
					(size 1 1)
					(thickness 0.15)
				)
				(justify mirror)
			)
		)
		(property "License" "Apache-2.0"
			(at 0 0 90)
			(unlocked yes)
			(layer "B.Fab")
			(hide yes)
			(effects
				(font
					(size 1 1)
					(thickness 0.15)
				)
				(justify mirror)
			)
		)
		(sheetname "/Power/")
		(sheetfile "power.kicad_sch")
		(attr smd)
		(fp_line
			(start -0.725 0.551)
			(end -0.277 0.551)
			(stroke
				(width 0.15)
				(type solid)
			)
			(layer "B.SilkS")
		)
		(fp_line
			(start -0.277 0.551)
			(end -0.277 0.75)
			(stroke
				(width 0.15)
				(type solid)
			)
			(layer "B.SilkS")
		)
		(fp_line
			(start -0.927 0.351)
			(end -0.725 0.551)
			(stroke
				(width 0.15)
				(type solid)
			)
			(layer "B.SilkS")
		)
		(fp_line
			(start -0.927 0.051)
			(end -0.927 0.351)
			(stroke
				(width 0.15)
				(type solid)
			)
			(layer "B.SilkS")
		)
		(fp_circle
			(center -0.9652 -0.9652)
			(end -0.9152 -0.9652)
			(stroke
				(width 0.15)
				(type solid)
			)
			(fill yes)
			(layer "B.SilkS")
		)
		(fp_line
			(start -1.12 1.16)
			(end 1.1 1.16)
			(stroke
				(width 0.05)
				(type solid)
			)
			(layer "B.CrtYd")
		)
		(fp_line
			(start -1.12 1.16)
			(end -1.12 -1.15)
			(stroke
				(width 0.05)
				(type solid)
			)
			(layer "B.CrtYd")
		)
		(fp_line
			(start 1.1 1.16)
			(end 1.1 -1.15)
			(stroke
				(width 0.05)
				(type solid)
			)
			(layer "B.CrtYd")
		)
		(fp_line
			(start -1.12 -1.15)
			(end 1.1 -1.15)
			(stroke
				(width 0.05)
				(type solid)
			)
			(layer "B.CrtYd")
		)
		(fp_line
			(start -0.652 0.425)
			(end -0.802 0.276)
			(stroke
				(width 0.15)
				(type solid)
			)
			(layer "B.Fab")
		)
		(fp_line
			(start 0.8 0.425)
			(end -0.652 0.425)
			(stroke
				(width 0.15)
				(type solid)
			)
			(layer "B.Fab")
		)
		(fp_line
			(start 0.8 0.425)
			(end 0.8 -0.424)
			(stroke
				(width 0.15)
				(type solid)
			)
			(layer "B.Fab")
		)
		(fp_line
			(start -0.802 0.276)
			(end -0.802 -0.424)
			(stroke
				(width 0.15)
				(type solid)
			)
			(layer "B.Fab")
		)
		(fp_line
			(start 0.8 -0.424)
			(end -0.802 -0.424)
			(stroke
				(width 0.15)
				(type solid)
			)
			(layer "B.Fab")
		)
		(fp_circle
			(center -0.9652 -0.9652)
			(end -0.9144 -0.9652)
			(stroke
				(width 0.15)
				(type solid)
			)
			(fill no)
			(layer "B.Fab")
		)
		(fp_text user "License: Apache-2.0"
			(at -1.12 -5.024 90)
			(layer "B.Fab")
			(effects
				(font
					(size 0.7 0.7)
					(thickness 0.15)
				)
				(justify left bottom mirror)
			)
		)
		(fp_text user "${REFERENCE}"
			(at -1.12 -3.824 90)
			(layer "B.Fab")
			(effects
				(font
					(size 0.7 0.7)
					(thickness 0.15)
				)
				(justify left bottom mirror)
			)
		)
		(fp_text user "Author: Antmicro"
			(at -1.12 -6.224 90)
			(layer "B.Fab")
			(effects
				(font
					(size 0.7 0.7)
					(thickness 0.15)
				)
				(justify left bottom mirror)
			)
		)
		(pad "1" smd rect
			(at -0.5 -0.65 270)
			(size 0.4 0.51)
			(layers "B.Cu" "B.Mask" "B.Paste")
			(net 282 "+1V15")
			(pinfunction "G")
			(pintype "input")
		)
		(pad "2" smd rect
			(at 0.498 -0.65 270)
			(size 0.4 0.51)
			(layers "B.Cu" "B.Mask" "B.Paste")
			(net 1 "GND")
			(pinfunction "S")
			(pintype "passive")
		)
		(pad "3" smd rect
			(at 0 0.652 270)
			(size 0.4 0.51)
			(layers "B.Cu" "B.Mask" "B.Paste")
			(net 891 "Net-(D40-C)")
			(pinfunction "D")
			(pintype "passive")
		)
	)
	(footprint "antmicro-footprints:TP_SMD_0.75mm"
		(layer "B.Cu")
		(at 185.54 85.47)
		(property "Reference" "TP123"
			(at 0.48 -0.4 0)
			(layer "B.SilkS")
			(effects
				(font
					(size 0.7 0.7)
					(thickness 0.15)
				)
				(justify right top mirror)
			)
		)
		(property "Value" "TP_0.75mm_SMD"
			(at 0 -1.2 0)
			(layer "B.Fab")
			(effects
				(font
					(size 0.7 0.7)
					(thickness 0.15)
				)
				(justify right top mirror)
			)
		)
		(property "Description" "SMT test point"
			(at 0 0 0)
			(layer "B.Fab")
			(hide yes)
			(effects
				(font
					(size 1.27 1.27)
					(thickness 0.15)
				)
				(justify mirror)
			)
		)
		(property "MPN" ""
			(at 0 0 180)
			(unlocked yes)
			(layer "B.Fab")
			(hide yes)
			(effects
				(font
					(size 1 1)
					(thickness 0.15)
				)
				(justify mirror)
			)
		)
		(property "Manufacturer" ""
			(at 0 0 180)
			(unlocked yes)
			(layer "B.Fab")
			(hide yes)
			(effects
				(font
					(size 1 1)
					(thickness 0.15)
				)
				(justify mirror)
			)
		)
		(property "Author" "Antmicro"
			(at 0 0 180)
			(unlocked yes)
			(layer "B.Fab")
			(hide yes)
			(effects
				(font
					(size 1 1)
					(thickness 0.15)
				)
				(justify mirror)
			)
		)
		(property "License" "Apache-2.0"
			(at 0 0 180)
			(unlocked yes)
			(layer "B.Fab")
			(hide yes)
			(effects
				(font
					(size 1 1)
					(thickness 0.15)
				)
				(justify mirror)
			)
		)
		(sheetname "/Power/")
		(sheetfile "power.kicad_sch")
		(attr exclude_from_pos_files exclude_from_bom)
		(fp_circle
			(center 0 0)
			(end 0.475 0)
			(stroke
				(width 0.05)
				(type default)
			)
			(fill no)
			(layer "B.CrtYd")
		)
		(fp_text user "License: Apache-2.0"
			(at -0.4 -5.101 0)
			(layer "B.Fab")
			(effects
				(font
					(size 0.7 0.7)
					(thickness 0.15)
				)
				(justify right top mirror)
			)
		)
		(fp_text user "Author: Antmicro"
			(at -0.4 -3.901 0)
			(layer "B.Fab")
			(effects
				(font
					(size 0.7 0.7)
					(thickness 0.15)
				)
				(justify right top mirror)
			)
		)
		(fp_text user "${REFERENCE}"
			(at -0.4 -2.7 0)
			(layer "B.Fab")
			(effects
				(font
					(size 0.7 0.7)
					(thickness 0.15)
				)
				(justify right top mirror)
			)
		)
		(pad "1" smd circle
			(at 0 0)
			(size 0.75 0.75)
			(layers "B.Cu" "B.Mask")
			(net 522 "/Power/USBPD1_HV")
			(pinfunction "1")
			(pintype "passive")
		)
	)
	(footprint "antmicro-footprints:TP_SMD_0.75mm"
		(layer "B.Cu")
		(at 124.5 103)
		(property "Reference" "TP37"
			(at 0.64 -0.52 0)
			(layer "B.SilkS")
			(effects
				(font
					(size 0.7 0.7)
					(thickness 0.15)
				)
				(justify right top mirror)
			)
		)
		(property "Value" "TP_0.75mm_SMD"
			(at 0 -1.2 0)
			(layer "B.Fab")
			(effects
				(font
					(size 0.7 0.7)
					(thickness 0.15)
				)
				(justify right top mirror)
			)
		)
		(property "Description" "SMT test point"
			(at 0 0 0)
			(layer "B.Fab")
			(hide yes)
			(effects
				(font
					(size 1.27 1.27)
					(thickness 0.15)
				)
				(justify mirror)
			)
		)
		(property "MPN" ""
			(at 0 0 180)
			(unlocked yes)
			(layer "B.Fab")
			(hide yes)
			(effects
				(font
					(size 1 1)
					(thickness 0.15)
				)
				(justify mirror)
			)
		)
		(property "Manufacturer" ""
			(at 0 0 180)
			(unlocked yes)
			(layer "B.Fab")
			(hide yes)
			(effects
				(font
					(size 1 1)
					(thickness 0.15)
				)
				(justify mirror)
			)
		)
		(property "Author" "Antmicro"
			(at 0 0 180)
			(unlocked yes)
			(layer "B.Fab")
			(hide yes)
			(effects
				(font
					(size 1 1)
					(thickness 0.15)
				)
				(justify mirror)
			)
		)
		(property "License" "Apache-2.0"
			(at 0 0 180)
			(unlocked yes)
			(layer "B.Fab")
			(hide yes)
			(effects
				(font
					(size 1 1)
					(thickness 0.15)
				)
				(justify mirror)
			)
		)
		(sheetname "/M.2/")
		(sheetfile "m2.kicad_sch")
		(attr exclude_from_pos_files exclude_from_bom)
		(fp_circle
			(center 0 0)
			(end 0.475 0)
			(stroke
				(width 0.05)
				(type default)
			)
			(fill no)
			(layer "B.CrtYd")
		)
		(fp_text user "License: Apache-2.0"
			(at -0.4 -5.101 0)
			(layer "B.Fab")
			(effects
				(font
					(size 0.7 0.7)
					(thickness 0.15)
				)
				(justify right top mirror)
			)
		)
		(fp_text user "Author: Antmicro"
			(at -0.4 -3.901 0)
			(layer "B.Fab")
			(effects
				(font
					(size 0.7 0.7)
					(thickness 0.15)
				)
				(justify right top mirror)
			)
		)
		(fp_text user "${REFERENCE}"
			(at -0.4 -2.7 0)
			(layer "B.Fab")
			(effects
				(font
					(size 0.7 0.7)
					(thickness 0.15)
				)
				(justify right top mirror)
			)
		)
		(pad "1" smd circle
			(at 0 0)
			(size 0.75 0.75)
			(layers "B.Cu" "B.Mask")
			(net 217 "/M.2/M2_M_SMB_DATA")
			(pinfunction "1")
			(pintype "passive")
		)
	)
	(footprint "antmicro-footprints:C_0402_1005Metric"
		(layer "B.Cu")
		(at 224.05 79.9)
		(descr "Capacitor SMD 0402")
		(tags "capacitor SMD 0402")
		(property "Reference" "C134"
			(at -1.75 0.6 0)
			(layer "B.SilkS")
			(effects
				(font
					(size 0.7 0.7)
					(thickness 0.15)
				)
				(justify right top mirror)
			)
		)
		(property "Value" "C_100n_0402"
			(at -1.022927 -2.155213 0)
			(layer "B.Fab")
			(effects
				(font
					(size 0.7 0.7)
					(thickness 0.15)
				)
				(justify right top mirror)
			)
		)
		(property "Datasheet" "https://www.murata.com/products/productdetail?partno=GRM155R61H104KE14%23"
			(at 0 0 0)
			(layer "B.Fab")
			(hide yes)
			(effects
				(font
					(size 1.27 1.27)
					(thickness 0.15)
				)
				(justify mirror)
			)
		)
		(property "Description" "SMD Multilayer Ceramic Capacitor, 0.1 µF, 50 V, 0402 [1005 Metric], ± 10%, X5R, GRM Series"
			(at 0 0 0)
			(layer "B.Fab")
			(hide yes)
			(effects
				(font
					(size 1.27 1.27)
					(thickness 0.15)
				)
				(justify mirror)
			)
		)
		(property "Manufacturer" "Murata"
			(at 0 0 180)
			(unlocked yes)
			(layer "B.Fab")
			(hide yes)
			(effects
				(font
					(size 1 1)
					(thickness 0.15)
				)
				(justify mirror)
			)
		)
		(property "MPN" "GRM155R61H104KE14D"
			(at 0 0 180)
			(unlocked yes)
			(layer "B.Fab")
			(hide yes)
			(effects
				(font
					(size 1 1)
					(thickness 0.15)
				)
				(justify mirror)
			)
		)
		(property "Val" "100n"
			(at 0 0 180)
			(unlocked yes)
			(layer "B.Fab")
			(hide yes)
			(effects
				(font
					(size 1 1)
					(thickness 0.15)
				)
				(justify mirror)
			)
		)
		(property "License" "Apache-2.0"
			(at 0 0 180)
			(unlocked yes)
			(layer "B.Fab")
			(hide yes)
			(effects
				(font
					(size 1 1)
					(thickness 0.15)
				)
				(justify mirror)
			)
		)
		(property "Author" "Antmicro"
			(at 0 0 180)
			(unlocked yes)
			(layer "B.Fab")
			(hide yes)
			(effects
				(font
					(size 1 1)
					(thickness 0.15)
				)
				(justify mirror)
			)
		)
		(property "Voltage" "50V"
			(at 0 0 180)
			(unlocked yes)
			(layer "B.Fab")
			(hide yes)
			(effects
				(font
					(size 1 1)
					(thickness 0.15)
				)
				(justify mirror)
			)
		)
		(property "Dielectric" "X5R"
			(at 0 0 180)
			(unlocked yes)
			(layer "B.Fab")
			(hide yes)
			(effects
				(font
					(size 1 1)
					(thickness 0.15)
				)
				(justify mirror)
			)
		)
		(sheetname "/USB Debug, PD/")
		(sheetfile "usb_debug_pd.kicad_sch")
		(attr smd)
		(fp_poly
			(pts
				(xy -0.925 0.47) (xy -0.925 -0.47) (xy 0.925 -0.47) (xy 0.925 0.47)
			)
			(stroke
				(width 0.05)
				(type default)
			)
			(fill no)
			(layer "B.CrtYd")
		)
		(fp_line
			(start -0.494 -0.248)
			(end -0.494 0.25)
			(stroke
				(width 0.15)
				(type solid)
			)
			(layer "B.Fab")
		)
		(fp_line
			(start -0.494 0.25)
			(end 0.504 0.25)
			(stroke
				(width 0.15)
				(type solid)
			)
			(layer "B.Fab")
		)
		(fp_line
			(start 0.504 -0.248)
			(end -0.494 -0.248)
			(stroke
				(width 0.15)
				(type solid)
			)
			(layer "B.Fab")
		)
		(fp_line
			(start 0.504 0.25)
			(end 0.504 -0.248)
			(stroke
				(width 0.15)
				(type solid)
			)
			(layer "B.Fab")
		)
		(fp_text user "${REFERENCE}"
			(at -0.939 -4.599 0)
			(layer "B.Fab")
			(effects
				(font
					(size 0.7 0.7)
					(thickness 0.15)
				)
				(justify right top mirror)
			)
		)
		(fp_text user "License: Apache-2.0"
			(at -0.939 -5.799 0)
			(layer "B.Fab")
			(effects
				(font
					(size 0.7 0.7)
					(thickness 0.15)
				)
				(justify right top mirror)
			)
		)
		(fp_text user "Author: Antmicro"
			(at -0.939 -3.399 0)
			(layer "B.Fab")
			(effects
				(font
					(size 0.7 0.7)
					(thickness 0.15)
				)
				(justify right top mirror)
			)
		)
		(pad "1" smd roundrect
			(at -0.48 0)
			(size 0.59 0.64)
			(layers "B.Cu" "B.Mask" "B.Paste")
			(roundrect_rratio 0.25)
			(net 334 "/USB Debug, PD/FTDI_3V3")
			(pintype "passive")
		)
		(pad "2" smd roundrect
			(at 0.48 0)
			(size 0.59 0.64)
			(layers "B.Cu" "B.Mask" "B.Paste")
			(roundrect_rratio 0.25)
			(net 1 "GND")
			(pintype "passive")
		)
	)
)
